FILE_TYPE=LIBRARY_PARTS;
primitive 'PXE1610B','PXE1610B_QFN';
  pin
    'BPWM1':
      PIN_NUMBER='(1)';
      OUTPUT_LOAD='(1.0,-1.0)';
    'APWM6':
      PIN_NUMBER='(2)';
      OUTPUT_LOAD='(1.0,-1.0)';
    'APWM5':
      PIN_NUMBER='(3)';
      OUTPUT_LOAD='(1.0,-1.0)';
    'APWM4':
      PIN_NUMBER='(4)';
      OUTPUT_LOAD='(1.0,-1.0)';
    'APWM3':
      PIN_NUMBER='(5)';
      OUTPUT_LOAD='(1.0,-1.0)';
    'APWM2':
      PIN_NUMBER='(6)';
      OUTPUT_LOAD='(1.0,-1.0)';
    'APWM1':
      PIN_NUMBER='(7)';
      OUTPUT_LOAD='(1.0,-1.0)';
    'SDA':
      PIN_NUMBER='(8)';
      BIDIRECTIONAL='TRUE';
      INPUT_LOAD='(-0.01,0.01)';
      OUTPUT_LOAD='(1.0,-1.0)';
    'SCL':
      PIN_NUMBER='(9)';
      BIDIRECTIONAL='TRUE';
      INPUT_LOAD='(-0.01,0.01)';
      OUTPUT_LOAD='(1.0,-1.0)';
    'RESET_N':
      PIN_NUMBER='(10)';
      INPUT_LOAD='(-0.01,0.01)';
    'AVRRDY':
      PIN_NUMBER='(11)';
      OUTPUT_LOAD='(1.0,-1.0)';
    'AVREN':
      PIN_NUMBER='(12)';
      INPUT_LOAD='(-0.01,0.01)';
    'VRHOT_N':
      PIN_NUMBER='(13)';
      OUTPUT_LOAD='(1.0,-1.0)';
    'PINALRT_N':
      PIN_NUMBER='(14)';
      OUTPUT_LOAD='(1.0,-1.0)';
    'MP0':
      PIN_NUMBER='(15)';
      BIDIRECTIONAL='TRUE';
      INPUT_LOAD='(-0.01,0.01)';
      OUTPUT_LOAD='(1.0,-1.0)';
    'MP1':
      PIN_NUMBER='(16)';
      BIDIRECTIONAL='TRUE';
      INPUT_LOAD='(-0.01,0.01)';
      OUTPUT_LOAD='(1.0,-1.0)';
    'VCLK':
      PIN_NUMBER='(17)';
      INPUT_LOAD='(-0.01,0.01)';
    'VDIO':
      PIN_NUMBER='(18)';
      BIDIRECTIONAL='TRUE';
      INPUT_LOAD='(-0.01,0.01)';
      OUTPUT_LOAD='(1.0,-1.0)';
    'VALRT_N':
      PIN_NUMBER='(19)';
      OUTPUT_LOAD='(1.0,-1.0)';
    'MP2':
      PIN_NUMBER='(20)';
      OUTPUT_LOAD='(1.0,-1.0)';
    'AVSEN':
      PIN_NUMBER='(21)';
      INPUT_LOAD='(-0.01,0.01)';
    'AVREF':
      PIN_NUMBER='(22)';
      INPUT_LOAD='(-0.01,0.01)';
    'AIREF1':
      PIN_NUMBER='(23)';
      INPUT_LOAD='(-0.01,0.01)';
    'AISEN1':
      PIN_NUMBER='(24)';
      INPUT_LOAD='(-0.01,0.01)';
    'AIREF2':
      PIN_NUMBER='(25)';
      INPUT_LOAD='(-0.01,0.01)';
    'AISEN2':
      PIN_NUMBER='(26)';
      INPUT_LOAD='(-0.01,0.01)';
    'AIREF3':
      PIN_NUMBER='(27)';
      INPUT_LOAD='(-0.01,0.01)';
    'AISEN3':
      PIN_NUMBER='(28)';
      INPUT_LOAD='(-0.01,0.01)';
    'AIREF4':
      PIN_NUMBER='(29)';
      INPUT_LOAD='(-0.01,0.01)';
    'AISEN4':
      PIN_NUMBER='(30)';
      INPUT_LOAD='(-0.01,0.01)';
    'AIREF5':
      PIN_NUMBER='(31)';
      INPUT_LOAD='(-0.01,0.01)';
    'AISEN5':
      PIN_NUMBER='(32)';
      INPUT_LOAD='(-0.01,0.01)';
    'AIREF6':
      PIN_NUMBER='(33)';
      INPUT_LOAD='(-0.01,0.01)';
    'AISEN6':
      PIN_NUMBER='(34)';
      INPUT_LOAD='(-0.01,0.01)';
    'BVSEN':
      PIN_NUMBER='(35)';
      INPUT_LOAD='(-0.01,0.01)';
    'BVREF':
      PIN_NUMBER='(36)';
      INPUT_LOAD='(-0.01,0.01)';
    'BIREF1':
      PIN_NUMBER='(37)';
      INPUT_LOAD='(-0.01,0.01)';
    'BISEN1':
      PIN_NUMBER='(38)';
      INPUT_LOAD='(-0.01,0.01)';
    'MP3':
      PIN_NUMBER='(39)';
      OUTPUT_LOAD='(1.0,-1.0)';
    'MP4':
      PIN_NUMBER='(40)';
      OUTPUT_LOAD='(1.0,-1.0)';
    'XADDR2':
      PIN_NUMBER='(41)';
      INPUT_LOAD='(-0.01,0.01)';
    'BTSEN':
      PIN_NUMBER='(42)';
      INPUT_LOAD='(-0.01,0.01)';
    'ATSEN':
      PIN_NUMBER='(43)';
      INPUT_LOAD='(-0.01,0.01)';
    'XADDR1':
      PIN_NUMBER='(44)';
      INPUT_LOAD='(-0.01,0.01)';
    'VINSEN':
      PIN_NUMBER='(45)';
      INPUT_LOAD='(-0.01,0.01)';
    'IINSEN':
      PIN_NUMBER='(46)';
      INPUT_LOAD='(-0.01,0.01)';
    'VDD':
      PIN_NUMBER='(47)';
      PINUSE='POWER';
      NO_LOAD_CHECK='Both';
      NO_IO_CHECK='Both';
      NO_ASSERT_CHECK='TRUE';
      NO_DIR_CHECK='TRUE';
      ALLOW_CONNECT='TRUE';
    'VD12':
      PIN_NUMBER='(48)';
      PINUSE='POWER';
      NO_LOAD_CHECK='Both';
      NO_IO_CHECK='Both';
      NO_ASSERT_CHECK='TRUE';
      NO_DIR_CHECK='TRUE';
      ALLOW_CONNECT='TRUE';
    'THPAD':
      PIN_NUMBER='(49)';
      PINUSE='GROUND';
      NO_LOAD_CHECK='Both';
      NO_IO_CHECK='Both';
      NO_ASSERT_CHECK='TRUE';
      NO_DIR_CHECK='TRUE';
      ALLOW_CONNECT='TRUE';
  end_pin;
  body
    PART_NAME='PXE1610B';
    PHYS_DES_PREFIX='EU';
  end_body;
end_primitive;

END.
